# SCM (Grand Teton) — schematic netlist excerpt (pin names and nets, part order shuffled) for the footprints in the layout excerpt that follows; sources: Cadence DE-HDL packaged netlist, KiCad conversion of 12092022_DA0F0TMDCD0_F0T_Management_Board_D_brd_V3_OCP.brd

R113  Q_RES  0 5% CHIP  pkg 0402LF  page 46 : A = IRQ_TPM_SPI_N ; B = IRQ_BMC_TPM_SPI_R_N
D20  SCHOTTKY_12  1N5819HW IC  pkg SOD123  page 32 : A = P3V3_AUX ; C = J7_P1

(kicad_pcb
	(version 20260206)
	(generator "pcbnew")
	(generator_version "10.0")
	(general
		(thickness 1.6)
		(legacy_teardrops no)
	)
	(paper "A4")
	(title_block
		(title "12092022_DA0F0TMDCD0_F0T_Management_Board_D_brd_V3_OCP.brd")
		(comment 1 "Grand Teton / footprints 618-619 of 1440")
	)
	(layers
		(0 "F.Cu" signal "TOP")
		(4 "In1.Cu" signal "GND")
		(6 "In2.Cu" signal "IN1")
		(8 "In3.Cu" signal "GND1")
		(10 "In4.Cu" signal "IN2")
		(12 "In5.Cu" signal "VCC")
		(14 "In6.Cu" signal "VCC1")
		(16 "In7.Cu" signal "IN3")
		(18 "In8.Cu" signal "GND2")
		(20 "In9.Cu" signal "IN4")
		(22 "In10.Cu" signal "GND3")
		(2 "B.Cu" signal "BOTTOM")
		(9 "F.Adhes" user "F.Adhesive")
		(11 "B.Adhes" user "B.Adhesive")
		(13 "F.Paste" user "Package Geometry/Pastemask Top")
		(15 "B.Paste" user "Package Geometry/Pastemask Bottom")
		(5 "F.SilkS" user "Ref Des/Silkscreen Top")
		(7 "B.SilkS" user "Ref Des/Silkscreen Bottom")
		(1 "F.Mask" user "Board Geometry/Soldermask Top")
		(3 "B.Mask" user "Board Geometry/Soldermask Bottom")
		(17 "Dwgs.User" user "User.Drawings")
		(19 "Cmts.User" user "User.Comments")
		(21 "Eco1.User" user "User.Eco1")
		(23 "Eco2.User" user "User.Eco2")
		(25 "Edge.Cuts" user "Board Geometry/Outline")
		(27 "Margin" user)
		(31 "F.CrtYd" user "Package Geometry/Place Bound Top")
		(29 "B.CrtYd" user "Package Geometry/Place Bound Bottom")
		(35 "F.Fab" user "Ref Des/Assembly Top")
		(33 "B.Fab" user "Ref Des/Assembly Bottom")
	)
	(footprint ""
		(layer "F.Cu")
		(at 73.66 -94.6658)
		(property "Reference" "R113"
			(at 0 0 0)
			(layer "F.SilkS")
			(hide yes)
			(effects
				(font
					(size 1.27 1.27)
				)
			)
		)
		(property "Value" ""
			(at 0 0 0)
			(layer "F.Fab")
			(effects
				(font
					(size 1.27 1.27)
				)
			)
		)
		(duplicate_pad_numbers_are_jumpers no)
		(fp_line
			(start -0.7874 -0.4064)
			(end 0.7874 -0.4064)
			(stroke
				(width 0.1524)
				(type default)
			)
			(layer "F.SilkS")
		)
		(fp_line
			(start -0.7874 0.4064)
			(end -0.7874 -0.4064)
			(stroke
				(width 0.1524)
				(type default)
			)
			(layer "F.SilkS")
		)
		(fp_line
			(start 0.7874 -0.4064)
			(end 0.7874 0.4064)
			(stroke
				(width 0.1524)
				(type default)
			)
			(layer "F.SilkS")
		)
		(fp_line
			(start 0.7874 0.4064)
			(end -0.7874 0.4064)
			(stroke
				(width 0.1524)
				(type default)
			)
			(layer "F.SilkS")
		)
		(fp_line
			(start -0.67945 -0.305054)
			(end -0.12065 -0.305054)
			(stroke
				(width 0.1)
				(type default)
			)
			(layer "F.Fab")
		)
		(fp_line
			(start -0.67945 0.3048)
			(end -0.67945 -0.305054)
			(stroke
				(width 0.1)
				(type default)
			)
			(layer "F.Fab")
		)
		(fp_line
			(start -0.12065 -0.305054)
			(end -0.12065 -0.2794)
			(stroke
				(width 0.1)
				(type default)
			)
			(layer "F.Fab")
		)
		(fp_line
			(start -0.12065 -0.2794)
			(end 0.12065 -0.2794)
			(stroke
				(width 0.1)
				(type default)
			)
			(layer "F.Fab")
		)
		(fp_line
			(start -0.12065 0.2794)
			(end -0.12065 0.3048)
			(stroke
				(width 0.1)
				(type default)
			)
			(layer "F.Fab")
		)
		(fp_line
			(start -0.12065 0.3048)
			(end -0.67945 0.3048)
			(stroke
				(width 0.1)
				(type default)
			)
			(layer "F.Fab")
		)
		(fp_line
			(start 0.120396 0.2794)
			(end -0.12065 0.2794)
			(stroke
				(width 0.1)
				(type default)
			)
			(layer "F.Fab")
		)
		(fp_line
			(start 0.120396 0.3048)
			(end 0.120396 0.2794)
			(stroke
				(width 0.1)
				(type default)
			)
			(layer "F.Fab")
		)
		(fp_line
			(start 0.12065 -0.3048)
			(end 0.67945 -0.3048)
			(stroke
				(width 0.1)
				(type default)
			)
			(layer "F.Fab")
		)
		(fp_line
			(start 0.12065 -0.2794)
			(end 0.12065 -0.3048)
			(stroke
				(width 0.1)
				(type default)
			)
			(layer "F.Fab")
		)
		(fp_line
			(start 0.67945 -0.3048)
			(end 0.67945 0.3048)
			(stroke
				(width 0.1)
				(type default)
			)
			(layer "F.Fab")
		)
		(fp_line
			(start 0.67945 0.3048)
			(end 0.120396 0.3048)
			(stroke
				(width 0.1)
				(type default)
			)
			(layer "F.Fab")
		)
		(pad "1" smd circle
			(at -0.40005 0)
			(size 0 0)
			(layers "F.Cu" "F.Mask" "F.Paste")
			(net "IRQ_TPM_SPI_N")
		)
		(pad "2" smd circle
			(at 0.40005 0)
			(size 0 0)
			(layers "F.Cu" "F.Mask" "F.Paste")
			(net "IRQ_BMC_TPM_SPI_R_N")
		)
	)
	(footprint ""
		(layer "F.Cu")
		(at 6.4516 -107.3404)
		(property "Reference" "D20"
			(at -4.8641 -1.58623 0)
			(unlocked yes)
			(layer "F.SilkS")
			(effects
				(font
					(size 0.7874 0.5842)
					(thickness 0.1524)
				)
				(justify left)
			)
		)
		(property "Value" ""
			(at 0 0 0)
			(layer "F.Fab")
			(effects
				(font
					(size 1.27 1.27)
				)
			)
		)
		(duplicate_pad_numbers_are_jumpers no)
		(fp_line
			(start -2.4638 -1.0414)
			(end 2.7178 -1.0414)
			(stroke
				(width 0.1524)
				(type default)
			)
			(layer "F.SilkS")
		)
		(fp_line
			(start -2.4638 1.0414)
			(end -2.4638 -1.0414)
			(stroke
				(width 0.1524)
				(type default)
			)
			(layer "F.SilkS")
		)
		(fp_line
			(start -0.508 -0.508)
			(end -0.508 0.5334)
			(stroke
				(width 0.1524)
				(type default)
			)
			(layer "F.SilkS")
		)
		(fp_line
			(start -0.508 0.5334)
			(end 0.1778 -0.0254)
			(stroke
				(width 0.1524)
				(type default)
			)
			(layer "F.SilkS")
		)
		(fp_line
			(start 0.1778 -0.0254)
			(end -0.4826 -0.4826)
			(stroke
				(width 0.1524)
				(type default)
			)
			(layer "F.SilkS")
		)
		(fp_line
			(start 0.254 -0.508)
			(end 0.254 0.5334)
			(stroke
				(width 0.1524)
				(type default)
			)
			(layer "F.SilkS")
		)
		(fp_line
			(start 2.4638 -1.0414)
			(end 2.4638 1.0414)
			(stroke
				(width 0.1524)
				(type default)
			)
			(layer "F.SilkS")
		)
		(fp_line
			(start 2.5908 -1.0414)
			(end 2.5908 1.0414)
			(stroke
				(width 0.1524)
				(type default)
			)
			(layer "F.SilkS")
		)
		(fp_line
			(start 2.7178 -1.0414)
			(end 2.7178 1.0414)
			(stroke
				(width 0.1524)
				(type default)
			)
			(layer "F.SilkS")
		)
		(fp_line
			(start 2.7178 1.0414)
			(end -2.4638 1.0414)
			(stroke
				(width 0.1524)
				(type default)
			)
			(layer "F.SilkS")
		)
		(fp_line
			(start -2.4638 -1.0414)
			(end 2.7178 -1.0414)
			(stroke
				(width 0.1)
				(type default)
			)
			(layer "F.Fab")
		)
		(fp_line
			(start -2.4638 1.0414)
			(end -2.4638 -1.0414)
			(stroke
				(width 0.1)
				(type default)
			)
			(layer "F.Fab")
		)
		(fp_line
			(start 2.7178 -1.0414)
			(end 2.7178 1.0414)
			(stroke
				(width 0.1)
				(type default)
			)
			(layer "F.Fab")
		)
		(fp_line
			(start 2.7178 1.0414)
			(end -2.4638 1.0414)
			(stroke
				(width 0.1)
				(type default)
			)
			(layer "F.Fab")
		)
		(fp_text user "+"
			(at -3.9624 -0.17145 0)
			(unlocked yes)
			(layer "F.SilkS")
			(effects
				(font
					(size 1.905 1.4224)
					(thickness 0.1524)
				)
				(justify left)
			)
		)
		(fp_text user "-"
			(at 2.4892 -0.26035 0)
			(unlocked yes)
			(layer "F.SilkS")
			(effects
				(font
					(size 1.905 1.4224)
					(thickness 0.1524)
				)
				(justify left)
			)
		)
		(fp_text user "+"
			(at -3.9624 -0.17145 0)
			(unlocked yes)
			(layer "F.Fab")
			(effects
				(font
					(size 1.905 1.4224)
					(thickness 0.1524)
				)
				(justify left)
			)
		)
		(fp_text user "-"
			(at 2.9845 -0.366268 0)
			(unlocked yes)
			(layer "F.Fab")
			(effects
				(font
					(size 1.905 1.4224)
					(thickness 0.1524)
				)
				(justify left)
			)
		)
		(pad "1" smd rect
			(at -1.724914 0)
			(size 1.1684 1.7526)
			(layers "F.Cu" "F.Mask" "F.Paste")
			(net "P3V3_AUX")
		)
		(pad "2" smd rect
			(at 1.724914 0)
			(size 1.1684 1.7526)
			(layers "F.Cu" "F.Mask" "F.Paste")
			(net "J7_P1")
		)
	)
)
